# BASEBOARD_FAB2 (Tioga Pass) — schematic netlist excerpt (pin names and nets, part order shuffled) for the footprints in the layout excerpt that follows; sources: Cadence DE-HDL packaged netlist, KiCad conversion of Wiwynn_Tioga_Pass_MB.brd

R7W13  RES  0.0 5% CHIP  pkg 0402  page 119 : A = FM_BMC_READY_N ; B = FM_BMC_READY_R_N
R8D39  RES  49.9K 1% CHIP  pkg 0402  page 196 : A = P5V ; B = A_PG_P5V
R9G13  RES  20.0 1% CHIP  pkg 0402  page 159 : A = SMB_OCP_LAN_STBY_LVC3_SCL ; B = SMB_SPRINGVILLE_STBY_LVC3_SCL

(kicad_pcb
	(version 20260206)
	(generator "pcbnew")
	(generator_version "10.0")
	(general
		(thickness 1.6)
		(legacy_teardrops no)
	)
	(paper "A4")
	(title_block
		(title "Wiwynn_Tioga_Pass_MB.brd")
		(comment 1 "Tioga Pass / footprints 2769-2771 of 4770")
	)
	(layers
		(0 "F.Cu" signal "TOP")
		(4 "In1.Cu" signal "L2GND")
		(6 "In2.Cu" signal "L3")
		(8 "In3.Cu" signal "L4GND")
		(10 "In4.Cu" signal "L5")
		(12 "In5.Cu" signal "L6GND")
		(14 "In6.Cu" signal "L7VCC")
		(16 "In7.Cu" signal "L8VCC")
		(18 "In8.Cu" signal "L9GND")
		(20 "In9.Cu" signal "L10")
		(22 "In10.Cu" signal "L11GND")
		(24 "In11.Cu" signal "L12")
		(26 "In12.Cu" signal "L13GND")
		(2 "B.Cu" signal "BOTTOM")
		(9 "F.Adhes" user "F.Adhesive")
		(11 "B.Adhes" user "B.Adhesive")
		(13 "F.Paste" user "Package Geometry/Pastemask Top")
		(15 "B.Paste" user "Package Geometry/Pastemask Bottom")
		(5 "F.SilkS" user "Ref Des/Silkscreen Top")
		(7 "B.SilkS" user "Ref Des/Silkscreen Bottom")
		(1 "F.Mask" user "Board Geometry/Soldermask Top")
		(3 "B.Mask" user "Board Geometry/Soldermask Bottom")
		(17 "Dwgs.User" user "User.Drawings")
		(19 "Cmts.User" user "User.Comments")
		(21 "Eco1.User" user "User.Eco1")
		(23 "Eco2.User" user "User.Eco2")
		(25 "Edge.Cuts" user "Board Geometry/Outline")
		(27 "Margin" user)
		(31 "F.CrtYd" user "Package Geometry/Place Bound Top")
		(29 "B.CrtYd" user "Package Geometry/Place Bound Bottom")
		(35 "F.Fab" user "Ref Des/Assembly Top")
		(33 "B.Fab" user "Ref Des/Assembly Bottom")
	)
	(footprint ""
		(layer "B.Cu")
		(at 490.3851 -120.7516 90)
		(property "Reference" "R9G13"
			(at 0 0 90)
			(layer "B.SilkS")
			(hide yes)
			(effects
				(font
					(size 1.27 1.27)
				)
				(justify mirror)
			)
		)
		(property "Value" ""
			(at 0 0 90)
			(layer "B.Fab")
			(effects
				(font
					(size 1.27 1.27)
				)
				(justify mirror)
			)
		)
		(duplicate_pad_numbers_are_jumpers no)
		(fp_poly
			(pts
				(xy 0.2794 -0.1016) (xy -0.2794 -0.1016) (xy -0.2794 0.9906) (xy 0.2794 0.9906)
			)
			(stroke
				(width 0)
				(type default)
			)
			(fill no)
			(layer "B.CrtYd")
		)
		(fp_line
			(start 0.2794 -0.1016)
			(end 0.2794 0.9906)
			(stroke
				(width 0.1)
				(type default)
			)
			(layer "B.Fab")
		)
		(fp_line
			(start -0.2794 -0.1016)
			(end 0.2794 -0.1016)
			(stroke
				(width 0.1)
				(type default)
			)
			(layer "B.Fab")
		)
		(fp_line
			(start 0.2794 0.9906)
			(end -0.2794 0.9906)
			(stroke
				(width 0.1)
				(type default)
			)
			(layer "B.Fab")
		)
		(fp_line
			(start -0.2794 0.9906)
			(end -0.2794 -0.1016)
			(stroke
				(width 0.1)
				(type default)
			)
			(layer "B.Fab")
		)
		(pad "1" smd rect
			(at 0 0 270)
			(size 0.508 0.508)
			(layers "B.Cu" "B.Mask" "B.Paste")
			(net "SMB_OCP_LAN_STBY_LVC3_SCL")
		)
		(pad "2" smd rect
			(at 0 0.889 270)
			(size 0.508 0.508)
			(layers "B.Cu" "B.Mask" "B.Paste")
			(net "SMB_SPRINGVILLE_STBY_LVC3_SCL")
		)
		(zone
			(layer "B.Cu")
			(hatch none 0.5)
			(connect_pads
				(clearance 0)
			)
			(min_thickness 0.25)
			(keepout
				(tracks allowed)
				(vias not_allowed)
				(pads allowed)
				(copperpour not_allowed)
				(footprints allowed)
			)
			(placement
				(enabled no)
				(sheetname "")
			)
			(fill
				(thermal_gap 0.5)
				(thermal_bridge_width 0.5)
				(island_removal_mode 0)
			)
			(polygon
				(pts
					(xy 490.6391 -121.0056) (xy 490.6391 -120.4976) (xy 491.0201 -120.4976) (xy 491.0201 -121.0056)
				)
			)
		)
		(zone
			(layer "B.Cu")
			(hatch none 0.5)
			(connect_pads
				(clearance 0)
			)
			(min_thickness 0.25)
			(keepout
				(tracks not_allowed)
				(vias allowed)
				(pads allowed)
				(copperpour not_allowed)
				(footprints allowed)
			)
			(placement
				(enabled no)
				(sheetname "")
			)
			(fill
				(thermal_gap 0.5)
				(thermal_bridge_width 0.5)
				(island_removal_mode 0)
			)
			(polygon
				(pts
					(xy 491.0201 -121.0056) (xy 491.0201 -120.4976) (xy 490.6391 -120.4976) (xy 490.6391 -121.0056)
				)
			)
		)
	)
	(footprint ""
		(layer "B.Cu")
		(at 408.051 -4.3815 180)
		(property "Reference" "R8D39"
			(at 0 0 0)
			(layer "B.SilkS")
			(hide yes)
			(effects
				(font
					(size 1.27 1.27)
				)
				(justify mirror)
			)
		)
		(property "Value" ""
			(at 0 0 0)
			(layer "B.Fab")
			(effects
				(font
					(size 1.27 1.27)
				)
				(justify mirror)
			)
		)
		(duplicate_pad_numbers_are_jumpers no)
		(fp_poly
			(pts
				(xy 0.2794 -0.1016) (xy -0.2794 -0.1016) (xy -0.2794 0.9906) (xy 0.2794 0.9906)
			)
			(stroke
				(width 0)
				(type default)
			)
			(fill no)
			(layer "B.CrtYd")
		)
		(fp_line
			(start 0.2794 0.9906)
			(end -0.2794 0.9906)
			(stroke
				(width 0.1)
				(type default)
			)
			(layer "B.Fab")
		)
		(fp_line
			(start 0.2794 -0.1016)
			(end 0.2794 0.9906)
			(stroke
				(width 0.1)
				(type default)
			)
			(layer "B.Fab")
		)
		(fp_line
			(start -0.2794 0.9906)
			(end -0.2794 -0.1016)
			(stroke
				(width 0.1)
				(type default)
			)
			(layer "B.Fab")
		)
		(fp_line
			(start -0.2794 -0.1016)
			(end 0.2794 -0.1016)
			(stroke
				(width 0.1)
				(type default)
			)
			(layer "B.Fab")
		)
		(pad "1" smd rect
			(at 0 0)
			(size 0.508 0.508)
			(layers "B.Cu" "B.Mask" "B.Paste")
			(net "P5V")
		)
		(pad "2" smd rect
			(at 0 0.889)
			(size 0.508 0.508)
			(layers "B.Cu" "B.Mask" "B.Paste")
			(net "A_PG_P5V")
		)
		(zone
			(layer "B.Cu")
			(hatch none 0.5)
			(connect_pads
				(clearance 0)
			)
			(min_thickness 0.25)
			(keepout
				(tracks not_allowed)
				(vias allowed)
				(pads allowed)
				(copperpour not_allowed)
				(footprints allowed)
			)
			(placement
				(enabled no)
				(sheetname "")
			)
			(fill
				(thermal_gap 0.5)
				(thermal_bridge_width 0.5)
				(island_removal_mode 0)
			)
			(polygon
				(pts
					(xy 407.797 -5.0165) (xy 408.305 -5.0165) (xy 408.305 -4.6355) (xy 407.797 -4.6355)
				)
			)
		)
		(zone
			(layer "B.Cu")
			(hatch none 0.5)
			(connect_pads
				(clearance 0)
			)
			(min_thickness 0.25)
			(keepout
				(tracks allowed)
				(vias not_allowed)
				(pads allowed)
				(copperpour not_allowed)
				(footprints allowed)
			)
			(placement
				(enabled no)
				(sheetname "")
			)
			(fill
				(thermal_gap 0.5)
				(thermal_bridge_width 0.5)
				(island_removal_mode 0)
			)
			(polygon
				(pts
					(xy 407.797 -4.6355) (xy 408.305 -4.6355) (xy 408.305 -5.0165) (xy 407.797 -5.0165)
				)
			)
		)
	)
	(footprint ""
		(layer "B.Cu")
		(at 381.7112 -90.53068 180)
		(property "Reference" "R7W13"
			(at 0.8382 -0.67818 180)
			(unlocked yes)
			(layer "B.SilkS")
			(effects
				(font
					(size 0.4064 0.254)
					(thickness 0.1524)
				)
				(justify left mirror)
			)
		)
		(property "Value" ""
			(at 0 0 0)
			(layer "B.Fab")
			(effects
				(font
					(size 1.27 1.27)
				)
				(justify mirror)
			)
		)
		(duplicate_pad_numbers_are_jumpers no)
		(fp_poly
			(pts
				(xy 0.2794 -0.1016) (xy -0.2794 -0.1016) (xy -0.2794 0.9906) (xy 0.2794 0.9906)
			)
			(stroke
				(width 0)
				(type default)
			)
			(fill no)
			(layer "B.CrtYd")
		)
		(fp_line
			(start 0.2794 0.9906)
			(end -0.2794 0.9906)
			(stroke
				(width 0.1)
				(type default)
			)
			(layer "B.Fab")
		)
		(fp_line
			(start 0.2794 -0.1016)
			(end 0.2794 0.9906)
			(stroke
				(width 0.1)
				(type default)
			)
			(layer "B.Fab")
		)
		(fp_line
			(start -0.2794 0.9906)
			(end -0.2794 -0.1016)
			(stroke
				(width 0.1)
				(type default)
			)
			(layer "B.Fab")
		)
		(fp_line
			(start -0.2794 -0.1016)
			(end 0.2794 -0.1016)
			(stroke
				(width 0.1)
				(type default)
			)
			(layer "B.Fab")
		)
		(pad "1" smd rect
			(at 0 0)
			(size 0.508 0.508)
			(layers "B.Cu" "B.Mask" "B.Paste")
			(net "FM_BMC_READY_N")
		)
		(pad "2" smd rect
			(at 0 0.889)
			(size 0.508 0.508)
			(layers "B.Cu" "B.Mask" "B.Paste")
			(net "FM_BMC_READY_R_N")
		)
		(zone
			(layer "B.Cu")
			(hatch none 0.5)
			(connect_pads
				(clearance 0)
			)
			(min_thickness 0.25)
			(keepout
				(tracks not_allowed)
				(vias allowed)
				(pads allowed)
				(copperpour not_allowed)
				(footprints allowed)
			)
			(placement
				(enabled no)
				(sheetname "")
			)
			(fill
				(thermal_gap 0.5)
				(thermal_bridge_width 0.5)
				(island_removal_mode 0)
			)
			(polygon
				(pts
					(xy 381.4572 -91.16568) (xy 381.9652 -91.16568) (xy 381.9652 -90.78468) (xy 381.4572 -90.78468)
				)
			)
		)
		(zone
			(layer "B.Cu")
			(hatch none 0.5)
			(connect_pads
				(clearance 0)
			)
			(min_thickness 0.25)
			(keepout
				(tracks allowed)
				(vias not_allowed)
				(pads allowed)
				(copperpour not_allowed)
				(footprints allowed)
			)
			(placement
				(enabled no)
				(sheetname "")
			)
			(fill
				(thermal_gap 0.5)
				(thermal_bridge_width 0.5)
				(island_removal_mode 0)
			)
			(polygon
				(pts
					(xy 381.4572 -90.78468) (xy 381.9652 -90.78468) (xy 381.9652 -91.16568) (xy 381.4572 -91.16568)
				)
			)
		)
	)
)
